(kicad_pcb
	(version 20260206)
	(generator "pcbnew")
	(generator_version "10.0")
	(general
		(thickness 1.6)
		(legacy_teardrops no)
	)
	(paper "A4")
	(title_block
		(title "Bryce Canyon_SCC_16316-1_OCP.brd")
		(comment 1 "Bryce Canyon / footprints 24-29 of 1561")
	)
	(layers
		(0 "F.Cu" signal "TOP")
		(4 "In1.Cu" signal "L2GND")
		(6 "In2.Cu" signal "L3")
		(8 "In3.Cu" signal "L4VCC")
		(10 "In4.Cu" signal "L5VCC")
		(12 "In5.Cu" signal "L6")
		(14 "In6.Cu" signal "L7GND")
		(2 "B.Cu" signal "BOTTOM")
		(9 "F.Adhes" user "F.Adhesive")
		(11 "B.Adhes" user "B.Adhesive")
		(13 "F.Paste" user "Package Geometry/Pastemask Top")
		(15 "B.Paste" user "Package Geometry/Pastemask Bottom")
		(5 "F.SilkS" user "Ref Des/Silkscreen Top")
		(7 "B.SilkS" user "Ref Des/Silkscreen Bottom")
		(1 "F.Mask" user "Board Geometry/Soldermask Top")
		(3 "B.Mask" user "Board Geometry/Soldermask Bottom")
		(17 "Dwgs.User" user "User.Drawings")
		(19 "Cmts.User" user "User.Comments")
		(21 "Eco1.User" user "User.Eco1")
		(23 "Eco2.User" user "User.Eco2")
		(25 "Edge.Cuts" user "Board Geometry/Outline")
		(27 "Margin" user)
		(31 "F.CrtYd" user "Package Geometry/Place Bound Top")
		(29 "B.CrtYd" user "Package Geometry/Place Bound Bottom")
		(35 "F.Fab" user "Ref Des/Assembly Top")
		(33 "B.Fab" user "Ref Des/Assembly Bottom")
	)
	(footprint ""
		(layer "F.Cu")
		(at 156.0576 -104.42956)
		(property "Reference" "DEBUG1"
			(at 0 0 0)
			(layer "F.SilkS")
			(hide yes)
			(effects
				(font
					(size 1.27 1.27)
				)
			)
		)
		(property "Value" "AMP-CONN4D-2-GP"
			(at -6.35 -0.254 0)
			(unlocked yes)
			(layer "F.Fab")
			(hide yes)
			(effects
				(font
					(size 1.016 1.016)
					(thickness 0.1524)
				)
			)
		)
		(property "Device Type" "G800MR304010HR"
			(at -6.35 -1.778 0)
			(unlocked yes)
			(layer "F.Fab")
			(hide yes)
			(effects
				(font
					(size 1.016 1.016)
					(thickness 0.1524)
				)
			)
		)
		(duplicate_pad_numbers_are_jumpers no)
		(fp_line
			(start -5.334 -3.2512)
			(end -5.334 3.2512)
			(stroke
				(width 0.1524)
				(type default)
			)
			(layer "F.SilkS")
		)
		(fp_line
			(start -5.334 3.2512)
			(end 5.334 3.2512)
			(stroke
				(width 0.1524)
				(type default)
			)
			(layer "F.SilkS")
		)
		(fp_line
			(start -4.2672 -3.3401)
			(end -3.2512 -3.3401)
			(stroke
				(width 0.3302)
				(type default)
			)
			(layer "F.SilkS")
		)
		(fp_line
			(start 5.334 -3.2512)
			(end -5.334 -3.2512)
			(stroke
				(width 0.1524)
				(type default)
			)
			(layer "F.SilkS")
		)
		(fp_line
			(start 5.334 3.2512)
			(end 5.334 -3.2512)
			(stroke
				(width 0.1524)
				(type default)
			)
			(layer "F.SilkS")
		)
		(fp_poly
			(pts
				(xy -3.81 -3.3274) (xy -3.175 -3.9624) (xy -4.445 -3.9624)
			)
			(stroke
				(width 0)
				(type default)
			)
			(fill yes)
			(layer "F.SilkS")
		)
		(fp_rect
			(start -5.08 2.4892)
			(end 5.08 -2.4892)
			(stroke
				(width 0)
				(type default)
			)
			(fill no)
			(layer "F.CrtYd")
		)
		(fp_poly
			(pts
				(xy 5.588 -2.4892) (xy -5.08 -2.4892) (xy -5.08 2.4892) (xy 5.08 2.4892) (xy 5.08 -2.4765) (xy 5.588 -2.4765)
				(xy 5.588 3.5052) (xy -5.588 3.5052) (xy -5.588 -3.5052) (xy 5.588 -3.5052)
			)
			(stroke
				(width 0)
				(type default)
			)
			(fill no)
			(layer "F.CrtYd")
		)
		(fp_rect
			(start -5.588 3.5052)
			(end 5.588 -3.5052)
			(stroke
				(width 0)
				(type default)
			)
			(fill no)
			(layer "F.Fab")
		)
		(pad "1" smd rect
			(at -3.81 -1.500124)
			(size 0.9906 2.9972)
			(layers "F.Cu" "F.Mask" "F.Paste")
			(net "SDB_CONN_PWR_2")
		)
		(pad "2" smd rect
			(at -1.27 1.500124)
			(size 0.9906 2.9972)
			(layers "F.Cu" "F.Mask" "F.Paste")
			(net "UART_SDB_TX")
		)
		(pad "3" smd rect
			(at 1.27 -1.500124)
			(size 0.9906 2.9972)
			(layers "F.Cu" "F.Mask" "F.Paste")
			(net "UART_SDB_RX")
		)
		(pad "4" smd rect
			(at 3.81 1.500124)
			(size 0.9906 2.9972)
			(layers "F.Cu" "F.Mask" "F.Paste")
			(net "GND")
		)
	)
	(footprint ""
		(layer "F.Cu")
		(at 123.317 -109.93628)
		(property "Reference" "TP151"
			(at 0 0 0)
			(layer "F.SilkS")
			(hide yes)
			(effects
				(font
					(size 1.27 1.27)
				)
			)
		)
		(property "Value" "TPAD28-2-GP"
			(at -0.0127 -1.6637 0)
			(unlocked yes)
			(layer "F.Fab")
			(hide yes)
			(effects
				(font
					(size 1.016 1.016)
					(thickness 0.1524)
				)
			)
		)
		(property "Device Type" "TPAD28"
			(at -0.0127 -3.1877 0)
			(unlocked yes)
			(layer "F.Fab")
			(hide yes)
			(effects
				(font
					(size 1.016 1.016)
					(thickness 0.1524)
				)
			)
		)
		(duplicate_pad_numbers_are_jumpers no)
		(fp_poly
			(pts
				(arc
					(start 0.3556 0)
					(mid -0.3556 0)
					(end 0.3556 0)
				)
			)
			(stroke
				(width 0)
				(type default)
			)
			(fill no)
			(layer "F.CrtYd")
		)
		(fp_poly
			(pts
				(arc
					(start 0.6096 0)
					(mid -0.6096 0)
					(end 0.6096 0)
				)
			)
			(stroke
				(width 0)
				(type default)
			)
			(fill no)
			(layer "F.Fab")
		)
		(pad "1" smd circle
			(at 0 0)
			(size 0.7112 0.7112)
			(layers "F.Cu" "F.Mask" "F.Paste")
			(net "INT_C1_CONN1")
		)
	)
	(footprint ""
		(layer "F.Cu")
		(at 67.9704 -72.6948 180)
		(property "Reference" "R429"
			(at 0 0 180)
			(layer "F.SilkS")
			(hide yes)
			(effects
				(font
					(size 1.27 1.27)
				)
			)
		)
		(property "Value" "1KR2F-3-GP"
			(at 0.064008 -3.993896 180)
			(unlocked yes)
			(layer "F.Fab")
			(hide yes)
			(effects
				(font
					(size 1.016 1.016)
					(thickness 0.1524)
				)
			)
		)
		(property "Device Type" "R402H16"
			(at 0.064008 -5.517896 180)
			(unlocked yes)
			(layer "F.Fab")
			(hide yes)
			(effects
				(font
					(size 1.016 1.016)
					(thickness 0.1524)
				)
			)
		)
		(duplicate_pad_numbers_are_jumpers no)
		(fp_line
			(start 0.508 -0.9398)
			(end -0.508 -0.9398)
			(stroke
				(width 0.1524)
				(type default)
			)
			(layer "F.SilkS")
		)
		(fp_line
			(start -0.508 -0.9398)
			(end -0.508 0.9398)
			(stroke
				(width 0.1524)
				(type default)
			)
			(layer "F.SilkS")
		)
		(fp_rect
			(start -0.508 0.9398)
			(end 0.508 -0.9398)
			(stroke
				(width 0)
				(type default)
			)
			(fill no)
			(layer "F.CrtYd")
		)
		(fp_rect
			(start -0.508 0.9398)
			(end 0.508 -0.9398)
			(stroke
				(width 0)
				(type default)
			)
			(fill no)
			(layer "F.Fab")
		)
		(pad "1" smd custom
			(at 0 -0.4445 180)
			(size 0.1397 0.1397)
			(layers "F.Cu" "F.Mask" "F.Paste")
			(net "P3V3")
			(options
				(clearance outline)
				(anchor circle)
			)
			(primitives
				(gr_poly
					(pts
						(arc
							(start -0.1778 -0.2794)
							(mid -0.249642 -0.249642)
							(end -0.2794 -0.1778)
						)
						(arc
							(start -0.2794 0.1778)
							(mid -0.249642 0.249642)
							(end -0.1778 0.2794)
						)
						(arc
							(start 0.1778 0.2794)
							(mid 0.249642 0.249642)
							(end 0.2794 0.1778)
						)
						(arc
							(start 0.2794 -0.1778)
							(mid 0.249642 -0.249642)
							(end 0.1778 -0.2794)
						)
					)
					(width 0)
					(fill yes)
				)
			)
		)
		(pad "2" smd custom
			(at 0 0.4445 180)
			(size 0.1397 0.1397)
			(layers "F.Cu" "F.Mask" "F.Paste")
			(net "I2C_DRIVE_FLT_LED_SCL6")
			(options
				(clearance outline)
				(anchor circle)
			)
			(primitives
				(gr_poly
					(pts
						(arc
							(start -0.1778 -0.2794)
							(mid -0.249642 -0.249642)
							(end -0.2794 -0.1778)
						)
						(arc
							(start -0.2794 0.1778)
							(mid -0.249642 0.249642)
							(end -0.1778 0.2794)
						)
						(arc
							(start 0.1778 0.2794)
							(mid 0.249642 0.249642)
							(end 0.2794 0.1778)
						)
						(arc
							(start 0.2794 -0.1778)
							(mid 0.249642 -0.249642)
							(end 0.1778 -0.2794)
						)
					)
					(width 0)
					(fill yes)
				)
			)
		)
	)
	(footprint ""
		(layer "F.Cu")
		(at 152.253442 -89.593166 -90)
		(property "Reference" "R289"
			(at 0 0 270)
			(layer "F.SilkS")
			(hide yes)
			(effects
				(font
					(size 1.27 1.27)
				)
			)
		)
		(property "Value" "0R2J-2-GP"
			(at 0.064008 -3.993896 270)
			(unlocked yes)
			(layer "F.Fab")
			(hide yes)
			(effects
				(font
					(size 1.016 1.016)
					(thickness 0.1524)
				)
			)
		)
		(property "Device Type" "R402H16"
			(at 0.064008 -5.517896 270)
			(unlocked yes)
			(layer "F.Fab")
			(hide yes)
			(effects
				(font
					(size 1.016 1.016)
					(thickness 0.1524)
				)
			)
		)
		(duplicate_pad_numbers_are_jumpers no)
		(fp_line
			(start -0.508 -0.9398)
			(end -0.508 0.9398)
			(stroke
				(width 0.1524)
				(type default)
			)
			(layer "F.SilkS")
		)
		(fp_line
			(start 0.508 -0.9398)
			(end -0.508 -0.9398)
			(stroke
				(width 0.1524)
				(type default)
			)
			(layer "F.SilkS")
		)
		(fp_rect
			(start -0.508 0.9398)
			(end 0.508 -0.9398)
			(stroke
				(width 0)
				(type default)
			)
			(fill no)
			(layer "F.CrtYd")
		)
		(fp_rect
			(start -0.508 0.9398)
			(end 0.508 -0.9398)
			(stroke
				(width 0)
				(type default)
			)
			(fill no)
			(layer "F.Fab")
		)
		(pad "1" smd custom
			(at 0 -0.4445 270)
			(size 0.1397 0.1397)
			(layers "F.Cu" "F.Mask" "F.Paste")
			(net "SAS_SMART_R_TX")
			(options
				(clearance outline)
				(anchor circle)
			)
			(primitives
				(gr_poly
					(pts
						(arc
							(start -0.1778 -0.2794)
							(mid -0.249642 -0.249642)
							(end -0.2794 -0.1778)
						)
						(arc
							(start -0.2794 0.1778)
							(mid -0.249642 0.249642)
							(end -0.1778 0.2794)
						)
						(arc
							(start 0.1778 0.2794)
							(mid 0.249642 0.249642)
							(end 0.2794 0.1778)
						)
						(arc
							(start 0.2794 -0.1778)
							(mid 0.249642 -0.249642)
							(end 0.1778 -0.2794)
						)
					)
					(width 0)
					(fill yes)
				)
			)
		)
		(pad "2" smd custom
			(at 0 0.4445 270)
			(size 0.1397 0.1397)
			(layers "F.Cu" "F.Mask" "F.Paste")
			(net "SAS_SMART_TX")
			(options
				(clearance outline)
				(anchor circle)
			)
			(primitives
				(gr_poly
					(pts
						(arc
							(start -0.1778 -0.2794)
							(mid -0.249642 -0.249642)
							(end -0.2794 -0.1778)
						)
						(arc
							(start -0.2794 0.1778)
							(mid -0.249642 0.249642)
							(end -0.1778 0.2794)
						)
						(arc
							(start 0.1778 0.2794)
							(mid 0.249642 0.249642)
							(end 0.2794 0.1778)
						)
						(arc
							(start 0.2794 -0.1778)
							(mid 0.249642 -0.249642)
							(end 0.1778 -0.2794)
						)
					)
					(width 0)
					(fill yes)
				)
			)
		)
	)
	(footprint ""
		(layer "F.Cu")
		(at 84.7725 -68.622164 -90)
		(property "Reference" "U24"
			(at 0 0 270)
			(layer "F.SilkS")
			(hide yes)
			(effects
				(font
					(size 1.27 1.27)
				)
			)
		)
		(property "Value" "SNLVC8T245DGVR-GP"
			(at 0 -11.1252 270)
			(unlocked yes)
			(layer "F.Fab")
			(hide yes)
			(effects
				(font
					(size 1.016 1.016)
					(thickness 0.1524)
				)
			)
		)
		(property "Device Type" "TVSOP24H48"
			(at 0 -12.6492 270)
			(unlocked yes)
			(layer "F.Fab")
			(hide yes)
			(effects
				(font
					(size 1.016 1.016)
					(thickness 0.1524)
				)
			)
		)
		(duplicate_pad_numbers_are_jumpers no)
		(fp_line
			(start -2.9337 1.397)
			(end 2.2987 1.397)
			(stroke
				(width 0.1524)
				(type default)
			)
			(layer "F.SilkS")
		)
		(fp_line
			(start -2.7559 1.397)
			(end -2.7559 3.8354)
			(stroke
				(width 0.508)
				(type default)
			)
			(layer "F.SilkS")
		)
		(fp_line
			(start 2.2987 1.397)
			(end 2.2987 -1.397)
			(stroke
				(width 0.1524)
				(type default)
			)
			(layer "F.SilkS")
		)
		(fp_line
			(start -2.5654 0)
			(end -2.9337 0.3683)
			(stroke
				(width 0.1524)
				(type default)
			)
			(layer "F.SilkS")
		)
		(fp_line
			(start -2.9337 -0.3683)
			(end -2.5654 0)
			(stroke
				(width 0.1524)
				(type default)
			)
			(layer "F.SilkS")
		)
		(fp_line
			(start -2.9337 -1.397)
			(end -2.9337 1.397)
			(stroke
				(width 0.1524)
				(type default)
			)
			(layer "F.SilkS")
		)
		(fp_line
			(start 2.2987 -1.397)
			(end -2.9337 -1.397)
			(stroke
				(width 0.1524)
				(type default)
			)
			(layer "F.SilkS")
		)
		(fp_rect
			(start -3.0099 4.0894)
			(end 3.0099 -4.0894)
			(stroke
				(width 0)
				(type default)
			)
			(fill no)
			(layer "F.CrtYd")
		)
		(fp_poly
			(pts
				(xy -3.0099 -4.0894) (xy 3.0099 -4.0894) (xy 3.0099 4.0894) (xy -3.0099 4.0894)
			)
			(stroke
				(width 0)
				(type default)
			)
			(fill no)
			(layer "F.Fab")
		)
		(pad "1" smd rect
			(at -2.19964 2.8194 270)
			(size 0.2032 1.524)
			(layers "F.Cu" "F.Mask" "F.Paste")
			(net "P3V3")
		)
		(pad "2" smd rect
			(at -1.79959 2.8194 270)
			(size 0.2032 1.524)
			(layers "F.Cu" "F.Mask" "F.Paste")
			(net "GND")
		)
		(pad "3" smd rect
			(at -1.39954 2.8194 270)
			(size 0.2032 1.524)
			(layers "F.Cu" "F.Mask" "F.Paste")
			(net "DEBUG_LOW_HEX_0")
		)
		(pad "4" smd rect
			(at -0.99949 2.8194 270)
			(size 0.2032 1.524)
			(layers "F.Cu" "F.Mask" "F.Paste")
			(net "DEBUG_LOW_HEX_1")
		)
		(pad "5" smd rect
			(at -0.59944 2.8194 270)
			(size 0.2032 1.524)
			(layers "F.Cu" "F.Mask" "F.Paste")
			(net "DEBUG_LOW_HEX_2")
		)
		(pad "6" smd rect
			(at -0.19939 2.8194 270)
			(size 0.2032 1.524)
			(layers "F.Cu" "F.Mask" "F.Paste")
			(net "DEBUG_LOW_HEX_3")
		)
		(pad "7" smd rect
			(at 0.19939 2.8194 270)
			(size 0.2032 1.524)
			(layers "F.Cu" "F.Mask" "F.Paste")
			(net "DEBUG_HIGH_HEX_0")
		)
		(pad "8" smd rect
			(at 0.59944 2.8194 270)
			(size 0.2032 1.524)
			(layers "F.Cu" "F.Mask" "F.Paste")
			(net "DEBUG_HIGH_HEX_1")
		)
		(pad "9" smd rect
			(at 0.99949 2.8194 270)
			(size 0.2032 1.524)
			(layers "F.Cu" "F.Mask" "F.Paste")
			(net "DEBUG_HIGH_HEX_2")
		)
		(pad "10" smd rect
			(at 1.39954 2.8194 270)
			(size 0.2032 1.524)
			(layers "F.Cu" "F.Mask" "F.Paste")
			(net "DEBUG_HIGH_HEX_3")
		)
		(pad "11" smd rect
			(at 1.79959 2.8194 270)
			(size 0.2032 1.524)
			(layers "F.Cu" "F.Mask" "F.Paste")
			(net "GND")
		)
		(pad "12" smd rect
			(at 2.19964 2.8194 270)
			(size 0.2032 1.524)
			(layers "F.Cu" "F.Mask" "F.Paste")
			(net "GND")
		)
		(pad "13" smd rect
			(at 2.19964 -2.8194 270)
			(size 0.2032 1.524)
			(layers "F.Cu" "F.Mask" "F.Paste")
			(net "GND")
		)
		(pad "14" smd rect
			(at 1.79959 -2.8194 270)
			(size 0.2032 1.524)
			(layers "F.Cu" "F.Mask" "F.Paste")
			(net "LED47")
		)
		(pad "15" smd rect
			(at 1.39954 -2.8194 270)
			(size 0.2032 1.524)
			(layers "F.Cu" "F.Mask" "F.Paste")
			(net "LED46")
		)
		(pad "16" smd rect
			(at 0.99949 -2.8194 270)
			(size 0.2032 1.524)
			(layers "F.Cu" "F.Mask" "F.Paste")
			(net "LED45")
		)
		(pad "17" smd rect
			(at 0.59944 -2.8194 270)
			(size 0.2032 1.524)
			(layers "F.Cu" "F.Mask" "F.Paste")
			(net "LED44")
		)
		(pad "18" smd rect
			(at 0.19939 -2.8194 270)
			(size 0.2032 1.524)
			(layers "F.Cu" "F.Mask" "F.Paste")
			(net "LED43")
		)
		(pad "19" smd rect
			(at -0.19939 -2.8194 270)
			(size 0.2032 1.524)
			(layers "F.Cu" "F.Mask" "F.Paste")
			(net "LED42")
		)
		(pad "20" smd rect
			(at -0.59944 -2.8194 270)
			(size 0.2032 1.524)
			(layers "F.Cu" "F.Mask" "F.Paste")
			(net "LED41")
		)
		(pad "21" smd rect
			(at -0.99949 -2.8194 270)
			(size 0.2032 1.524)
			(layers "F.Cu" "F.Mask" "F.Paste")
			(net "LED40")
		)
		(pad "22" smd rect
			(at -1.39954 -2.8194 270)
			(size 0.2032 1.524)
			(layers "F.Cu" "F.Mask" "F.Paste")
			(net "LS_EN_U24")
		)
		(pad "23" smd rect
			(at -1.79959 -2.8194 270)
			(size 0.2032 1.524)
			(layers "F.Cu" "F.Mask" "F.Paste")
			(net "P1V8_E")
		)
		(pad "24" smd rect
			(at -2.19964 -2.8194 270)
			(size 0.2032 1.524)
			(layers "F.Cu" "F.Mask" "F.Paste")
			(net "P1V8_E")
		)
	)
	(footprint ""
		(layer "F.Cu")
		(at 21.7932 -51.9176 90)
		(property "Reference" "C714"
			(at 0 0 90)
			(layer "F.SilkS")
			(hide yes)
			(effects
				(font
					(size 1.27 1.27)
				)
			)
		)
		(property "Value" "SC1U16V3KX-5GP"
			(at 0 -2.8194 90)
			(unlocked yes)
			(layer "F.Fab")
			(hide yes)
			(effects
				(font
					(size 1.016 1.016)
					(thickness 0.1524)
				)
			)
		)
		(property "Device Type" "C603H36"
			(at 0 -4.3434 90)
			(unlocked yes)
			(layer "F.Fab")
			(hide yes)
			(effects
				(font
					(size 1.016 1.016)
					(thickness 0.1524)
				)
			)
		)
		(duplicate_pad_numbers_are_jumpers no)
		(fp_line
			(start 0.508 0)
			(end -0.508 0)
			(stroke
				(width 0.2032)
				(type default)
			)
			(layer "F.SilkS")
		)
		(fp_rect
			(start -0.5842 1.3335)
			(end 0.5842 -1.3335)
			(stroke
				(width 0)
				(type default)
			)
			(fill no)
			(layer "F.CrtYd")
		)
		(fp_rect
			(start -0.5842 1.3335)
			(end 0.5842 -1.3335)
			(stroke
				(width 0)
				(type default)
			)
			(fill no)
			(layer "F.Fab")
		)
		(pad "1" smd custom
			(at 0 -0.762 90)
			(size 0.2159 0.2159)
			(layers "F.Cu" "F.Mask" "F.Paste")
			(net "MB0_VCAP_R")
			(options
				(clearance outline)
				(anchor circle)
			)
			(primitives
				(gr_poly
					(pts
						(arc
							(start -0.3302 -0.4318)
							(mid -0.402042 -0.402042)
							(end -0.4318 -0.3302)
						)
						(arc
							(start -0.4318 0.3302)
							(mid -0.402042 0.402042)
							(end -0.3302 0.4318)
						)
						(arc
							(start 0.3302 0.4318)
							(mid 0.402042 0.402042)
							(end 0.4318 0.3302)
						)
						(arc
							(start 0.4318 -0.3302)
							(mid 0.402042 -0.402042)
							(end 0.3302 -0.4318)
						)
					)
					(width 0)
					(fill yes)
				)
			)
		)
		(pad "2" smd custom
			(at 0 0.762 90)
			(size 0.2159 0.2159)
			(layers "F.Cu" "F.Mask" "F.Paste")
			(net "AGND_CURRENT_MON")
			(options
				(clearance outline)
				(anchor circle)
			)
			(primitives
				(gr_poly
					(pts
						(arc
							(start -0.3302 -0.4318)
							(mid -0.402042 -0.402042)
							(end -0.4318 -0.3302)
						)
						(arc
							(start -0.4318 0.3302)
							(mid -0.402042 0.402042)
							(end -0.3302 0.4318)
						)
						(arc
							(start 0.3302 0.4318)
							(mid 0.402042 0.402042)
							(end 0.4318 0.3302)
						)
						(arc
							(start 0.4318 -0.3302)
							(mid 0.402042 -0.402042)
							(end 0.3302 -0.4318)
						)
					)
					(width 0)
					(fill yes)
				)
			)
		)
	)
)
